# T6G (Grand Teton) — schematic netlist excerpt (pin names and nets, part order shuffled) for the footprints in the layout excerpt that follows; sources: Cadence DE-HDL packaged netlist, KiCad conversion of 04192023_DAF0TMB3IC0_F0TG_MB_C_brd_V02_OCP.brd

U142  LT6700CS61TRPBF  LT6700CS6-1#TRPBF EMPTY  pkg TSOT23-6_0-95_2-9X1-625  page 267
  OUTA  = A_HSC_LOW_GATE
  GND  = GND
  \ina+\  = A_HSC_LOW
  \inb-\  = A_HSC_HIGH
  VS  = U142_VS
  OUTB  = HSC_D_OC

PC629_4  Q_CAP  22UF 16V 20% X6S  pkg C0805  page 223 : A = SW_P12V_AUX_PVDDIO_P1_FLT ; B = GND
PC269_2  Q_CAP  22UF 16V 20% X6S  pkg C0805  page 211 : A = SW_P12V_AUX_PVDDCR_CPU0_P1_FLT ; B = GND

(kicad_pcb
	(version 20260206)
	(generator "pcbnew")
	(generator_version "10.0")
	(general
		(thickness 1.6)
		(legacy_teardrops no)
	)
	(paper "A4")
	(title_block
		(title "04192023_DAF0TMB3IC0_F0TG_MB_C_brd_V02_OCP.brd")
		(comment 1 "Grand Teton / footprints 7106-7108 of 8354")
	)
	(layers
		(0 "F.Cu" signal "TOP")
		(4 "In1.Cu" signal "GND")
		(6 "In2.Cu" signal "IN1")
		(8 "In3.Cu" signal "GND1")
		(10 "In4.Cu" signal "IN2")
		(12 "In5.Cu" signal "GND2")
		(14 "In6.Cu" signal "IN3")
		(16 "In7.Cu" signal "GND3")
		(18 "In8.Cu" signal "VCC")
		(20 "In9.Cu" signal "VCC1")
		(22 "In10.Cu" signal "GND4")
		(24 "In11.Cu" signal "IN4")
		(26 "In12.Cu" signal "GND5")
		(28 "In13.Cu" signal "IN5")
		(30 "In14.Cu" signal "GND6")
		(32 "In15.Cu" signal "IN6")
		(34 "In16.Cu" signal "GND7")
		(2 "B.Cu" signal "BOTTOM")
		(9 "F.Adhes" user "F.Adhesive")
		(11 "B.Adhes" user "B.Adhesive")
		(13 "F.Paste" user "Package Geometry/Pastemask Top")
		(15 "B.Paste" user "Package Geometry/Pastemask Bottom")
		(5 "F.SilkS" user "Ref Des/Silkscreen Top")
		(7 "B.SilkS" user "Ref Des/Silkscreen Bottom")
		(1 "F.Mask" user "Board Geometry/Soldermask Top")
		(3 "B.Mask" user "Board Geometry/Soldermask Bottom")
		(17 "Dwgs.User" user "User.Drawings")
		(19 "Cmts.User" user "User.Comments")
		(21 "Eco1.User" user "User.Eco1")
		(23 "Eco2.User" user "User.Eco2")
		(25 "Edge.Cuts" user "Board Geometry/Outline")
		(27 "Margin" user)
		(31 "F.CrtYd" user "Package Geometry/Place Bound Top")
		(29 "B.CrtYd" user "Package Geometry/Place Bound Bottom")
		(35 "F.Fab" user "Ref Des/Assembly Top")
		(33 "B.Fab" user "Ref Des/Assembly Bottom")
	)
	(footprint ""
		(layer "B.Cu")
		(at 87.432134 -182.607966 -90)
		(property "Reference" "PC269_2"
			(at 0 0 90)
			(layer "B.SilkS")
			(hide yes)
			(effects
				(font
					(size 1.27 1.27)
				)
				(justify mirror)
			)
		)
		(property "Value" ""
			(at 0 0 90)
			(layer "B.Fab")
			(effects
				(font
					(size 1.27 1.27)
				)
				(justify mirror)
			)
		)
		(duplicate_pad_numbers_are_jumpers no)
		(fp_line
			(start -1.524 0.762)
			(end 1.524 0.762)
			(stroke
				(width 0.1524)
				(type default)
			)
			(layer "B.SilkS")
		)
		(fp_line
			(start 1.524 0.762)
			(end 1.524 -0.762)
			(stroke
				(width 0.1524)
				(type default)
			)
			(layer "B.SilkS")
		)
		(fp_line
			(start -1.524 -0.762)
			(end -1.524 0.762)
			(stroke
				(width 0.1524)
				(type default)
			)
			(layer "B.SilkS")
		)
		(fp_line
			(start 1.524 -0.762)
			(end -1.524 -0.762)
			(stroke
				(width 0.1524)
				(type default)
			)
			(layer "B.SilkS")
		)
		(fp_line
			(start -1.1049 0.724916)
			(end -1.1049 -0.724916)
			(stroke
				(width 0.1)
				(type default)
			)
			(layer "B.Fab")
		)
		(fp_line
			(start 1.1049 0.724916)
			(end -1.1049 0.724916)
			(stroke
				(width 0.1)
				(type default)
			)
			(layer "B.Fab")
		)
		(fp_line
			(start -1.1049 -0.724916)
			(end 1.1049 -0.724916)
			(stroke
				(width 0.1)
				(type default)
			)
			(layer "B.Fab")
		)
		(fp_line
			(start 1.1049 -0.724916)
			(end 1.1049 0.724916)
			(stroke
				(width 0.1)
				(type default)
			)
			(layer "B.Fab")
		)
		(pad "1" smd rect
			(at 0.889 0 270)
			(size 1.016 1.27)
			(layers "B.Cu" "B.Mask" "B.Paste")
			(net "SW_P12V_AUX_PVDDCR_CPU0_P1_FLT")
		)
		(pad "2" smd rect
			(at -0.889 0 270)
			(size 1.016 1.27)
			(layers "B.Cu" "B.Mask" "B.Paste")
			(net "GND")
		)
	)
	(footprint ""
		(layer "B.Cu")
		(at 179.162964 -425.394882 90)
		(property "Reference" "U142"
			(at 3.405632 2.674874 0)
			(unlocked yes)
			(layer "B.SilkS")
			(effects
				(font
					(size 0.7874 0.5842)
					(thickness 0.1524)
				)
				(justify left mirror)
			)
		)
		(property "Value" ""
			(at 0 0 90)
			(layer "B.Fab")
			(effects
				(font
					(size 1.27 1.27)
				)
				(justify mirror)
			)
		)
		(duplicate_pad_numbers_are_jumpers no)
		(fp_line
			(start 2.046478 -1.450086)
			(end 2.046478 1.450086)
			(stroke
				(width 0.1524)
				(type default)
			)
			(layer "B.SilkS")
		)
		(fp_line
			(start 0.484886 -1.450086)
			(end 2.046478 -1.450086)
			(stroke
				(width 0.1524)
				(type default)
			)
			(layer "B.SilkS")
		)
		(fp_line
			(start -0.484886 -1.450086)
			(end 0 -0.762)
			(stroke
				(width 0.1524)
				(type default)
			)
			(layer "B.SilkS")
		)
		(fp_line
			(start -2.046478 -1.450086)
			(end -0.484886 -1.450086)
			(stroke
				(width 0.1524)
				(type default)
			)
			(layer "B.SilkS")
		)
		(fp_line
			(start 0 -0.762)
			(end 0.484886 -1.450086)
			(stroke
				(width 0.1524)
				(type default)
			)
			(layer "B.SilkS")
		)
		(fp_line
			(start 2.046478 1.450086)
			(end -2.046478 1.450086)
			(stroke
				(width 0.1524)
				(type default)
			)
			(layer "B.SilkS")
		)
		(fp_line
			(start -2.046478 1.450086)
			(end -2.046478 -1.450086)
			(stroke
				(width 0.1524)
				(type default)
			)
			(layer "B.SilkS")
		)
		(fp_poly
			(pts
				(xy 2.2352 -0.94996) (xy 3.2512 -0.44196) (xy 3.2512 -1.45796)
			)
			(stroke
				(width 0)
				(type default)
			)
			(fill yes)
			(layer "B.SilkS")
		)
		(fp_line
			(start 0.87503 -1.450086)
			(end 0.87503 1.450086)
			(stroke
				(width 0.1)
				(type default)
			)
			(layer "B.Fab")
		)
		(fp_line
			(start -0.87503 -1.450086)
			(end 0.87503 -1.450086)
			(stroke
				(width 0.1)
				(type default)
			)
			(layer "B.Fab")
		)
		(fp_line
			(start 0.87503 1.450086)
			(end -0.87503 1.450086)
			(stroke
				(width 0.1)
				(type default)
			)
			(layer "B.Fab")
		)
		(fp_line
			(start -0.87503 1.450086)
			(end -0.87503 -1.450086)
			(stroke
				(width 0.1)
				(type default)
			)
			(layer "B.Fab")
		)
		(fp_poly
			(pts
				(xy 3.2512 -0.44196) (xy 3.2512 -1.45796) (xy 2.2352 -0.94996)
			)
			(stroke
				(width 0)
				(type default)
			)
			(fill yes)
			(layer "B.Fab")
		)
		(pad "1" smd rect
			(at 1.309878 -0.94996 180)
			(size 0.635 1.2192)
			(layers "B.Cu" "B.Mask" "B.Paste")
			(net "A_HSC_LOW_GATE")
		)
		(pad "2" smd rect
			(at 1.309878 0 180)
			(size 0.635 1.2192)
			(layers "B.Cu" "B.Mask" "B.Paste")
			(net "GND")
		)
		(pad "3" smd rect
			(at 1.309878 0.94996 180)
			(size 0.635 1.2192)
			(layers "B.Cu" "B.Mask" "B.Paste")
			(net "A_HSC_LOW")
		)
		(pad "4" smd rect
			(at -1.309878 0.94996 180)
			(size 0.635 1.2192)
			(layers "B.Cu" "B.Mask" "B.Paste")
			(net "A_HSC_HIGH")
		)
		(pad "5" smd rect
			(at -1.309878 0 180)
			(size 0.635 1.2192)
			(layers "B.Cu" "B.Mask" "B.Paste")
			(net "U142_VS")
		)
		(pad "6" smd rect
			(at -1.309878 -0.94996 180)
			(size 0.635 1.2192)
			(layers "B.Cu" "B.Mask" "B.Paste")
			(net "HSC_D_OC")
		)
	)
	(footprint ""
		(layer "B.Cu")
		(at 29.722318 -350.660716 -90)
		(property "Reference" "PC629_4"
			(at 0 0 90)
			(layer "B.SilkS")
			(hide yes)
			(effects
				(font
					(size 1.27 1.27)
				)
				(justify mirror)
			)
		)
		(property "Value" ""
			(at 0 0 90)
			(layer "B.Fab")
			(effects
				(font
					(size 1.27 1.27)
				)
				(justify mirror)
			)
		)
		(duplicate_pad_numbers_are_jumpers no)
		(fp_line
			(start -1.524 0.762)
			(end 1.524 0.762)
			(stroke
				(width 0.1524)
				(type default)
			)
			(layer "B.SilkS")
		)
		(fp_line
			(start 1.524 0.762)
			(end 1.524 -0.762)
			(stroke
				(width 0.1524)
				(type default)
			)
			(layer "B.SilkS")
		)
		(fp_line
			(start -1.524 -0.762)
			(end -1.524 0.762)
			(stroke
				(width 0.1524)
				(type default)
			)
			(layer "B.SilkS")
		)
		(fp_line
			(start 1.524 -0.762)
			(end -1.524 -0.762)
			(stroke
				(width 0.1524)
				(type default)
			)
			(layer "B.SilkS")
		)
		(fp_line
			(start -1.1049 0.724916)
			(end -1.1049 -0.724916)
			(stroke
				(width 0.1)
				(type default)
			)
			(layer "B.Fab")
		)
		(fp_line
			(start 1.1049 0.724916)
			(end -1.1049 0.724916)
			(stroke
				(width 0.1)
				(type default)
			)
			(layer "B.Fab")
		)
		(fp_line
			(start -1.1049 -0.724916)
			(end 1.1049 -0.724916)
			(stroke
				(width 0.1)
				(type default)
			)
			(layer "B.Fab")
		)
		(fp_line
			(start 1.1049 -0.724916)
			(end 1.1049 0.724916)
			(stroke
				(width 0.1)
				(type default)
			)
			(layer "B.Fab")
		)
		(pad "1" smd rect
			(at 0.889 0 270)
			(size 1.016 1.27)
			(layers "B.Cu" "B.Mask" "B.Paste")
			(net "SW_P12V_AUX_PVDDIO_P1_FLT")
		)
		(pad "2" smd rect
			(at -0.889 0 270)
			(size 1.016 1.27)
			(layers "B.Cu" "B.Mask" "B.Paste")
			(net "GND")
		)
	)
)
